# BASEBOARD_FAB2 (Tioga Pass) — schematic netlist excerpt (pin names and nets, part order shuffled) for the footprints in the layout excerpt that follows; sources: Cadence DE-HDL packaged netlist, KiCad conversion of Wiwynn_Tioga_Pass_MB.brd

R25W9  120R2F-GP  1%  pkg RCL_GP  page 151 : \1\ = GND ; \2\ = BMC_M_BA0

EU8E1  CSD87384M  IC  pkg SM  page 240
  TG  = VR_P3V3_STBY_UGATE
  VIN  = VR_FET_SW_P12V_STBY_P3V3_STBY
  PGND  = GND
  BG  = VR_P3V3_STBY_LGATE
  VSW  = VR_P3V3_STBY_PHASE

R1D43  RES  7.5K 1% CHIP  pkg 0402  page 199 : A = A_HSC_OV ; B = AGND_HSC

(kicad_pcb
	(version 20260206)
	(generator "pcbnew")
	(generator_version "10.0")
	(general
		(thickness 1.6)
		(legacy_teardrops no)
	)
	(paper "A4")
	(title_block
		(title "Wiwynn_Tioga_Pass_MB.brd")
		(comment 1 "Tioga Pass / footprints 1-3 of 4770")
	)
	(layers
		(0 "F.Cu" signal "TOP")
		(4 "In1.Cu" signal "L2GND")
		(6 "In2.Cu" signal "L3")
		(8 "In3.Cu" signal "L4GND")
		(10 "In4.Cu" signal "L5")
		(12 "In5.Cu" signal "L6GND")
		(14 "In6.Cu" signal "L7VCC")
		(16 "In7.Cu" signal "L8VCC")
		(18 "In8.Cu" signal "L9GND")
		(20 "In9.Cu" signal "L10")
		(22 "In10.Cu" signal "L11GND")
		(24 "In11.Cu" signal "L12")
		(26 "In12.Cu" signal "L13GND")
		(2 "B.Cu" signal "BOTTOM")
		(9 "F.Adhes" user "F.Adhesive")
		(11 "B.Adhes" user "B.Adhesive")
		(13 "F.Paste" user "Package Geometry/Pastemask Top")
		(15 "B.Paste" user "Package Geometry/Pastemask Bottom")
		(5 "F.SilkS" user "Ref Des/Silkscreen Top")
		(7 "B.SilkS" user "Ref Des/Silkscreen Bottom")
		(1 "F.Mask" user "Board Geometry/Soldermask Top")
		(3 "B.Mask" user "Board Geometry/Soldermask Bottom")
		(17 "Dwgs.User" user "User.Drawings")
		(19 "Cmts.User" user "User.Comments")
		(21 "Eco1.User" user "User.Eco1")
		(23 "Eco2.User" user "User.Eco2")
		(25 "Edge.Cuts" user "Board Geometry/Outline")
		(27 "Margin" user)
		(31 "F.CrtYd" user "Package Geometry/Place Bound Top")
		(29 "B.CrtYd" user "Package Geometry/Place Bound Bottom")
		(35 "F.Fab" user "Ref Des/Assembly Top")
		(33 "B.Fab" user "Ref Des/Assembly Bottom")
	)
	(footprint ""
		(layer "F.Cu")
		(at 22.225 -70.866)
		(property "Reference" "R1D43"
			(at 0 0 0)
			(layer "F.SilkS")
			(hide yes)
			(effects
				(font
					(size 1.27 1.27)
				)
			)
		)
		(property "Value" ""
			(at 0 0 0)
			(layer "F.Fab")
			(effects
				(font
					(size 1.27 1.27)
				)
			)
		)
		(duplicate_pad_numbers_are_jumpers no)
		(fp_poly
			(pts
				(xy -0.2794 -0.1016) (xy 0.2794 -0.1016) (xy 0.2794 0.9906) (xy -0.2794 0.9906)
			)
			(stroke
				(width 0)
				(type default)
			)
			(fill no)
			(layer "F.CrtYd")
		)
		(fp_line
			(start -0.2794 -0.1016)
			(end -0.2794 0.9906)
			(stroke
				(width 0.1)
				(type default)
			)
			(layer "F.Fab")
		)
		(fp_line
			(start -0.2794 0.9906)
			(end 0.2794 0.9906)
			(stroke
				(width 0.1)
				(type default)
			)
			(layer "F.Fab")
		)
		(fp_line
			(start 0.2794 -0.1016)
			(end -0.2794 -0.1016)
			(stroke
				(width 0.1)
				(type default)
			)
			(layer "F.Fab")
		)
		(fp_line
			(start 0.2794 0.9906)
			(end 0.2794 -0.1016)
			(stroke
				(width 0.1)
				(type default)
			)
			(layer "F.Fab")
		)
		(pad "1" smd rect
			(at 0 0)
			(size 0.508 0.508)
			(layers "F.Cu" "F.Mask" "F.Paste")
			(net "A_HSC_OV")
		)
		(pad "2" smd rect
			(at 0 0.889)
			(size 0.508 0.508)
			(layers "F.Cu" "F.Mask" "F.Paste")
			(net "AGND_HSC")
		)
		(zone
			(layer "F.Cu")
			(hatch none 0.5)
			(connect_pads
				(clearance 0)
			)
			(min_thickness 0.25)
			(keepout
				(tracks allowed)
				(vias not_allowed)
				(pads allowed)
				(copperpour not_allowed)
				(footprints allowed)
			)
			(placement
				(enabled no)
				(sheetname "")
			)
			(fill
				(thermal_gap 0.5)
				(thermal_bridge_width 0.5)
				(island_removal_mode 0)
			)
			(polygon
				(pts
					(xy 21.971 -70.612) (xy 22.479 -70.612) (xy 22.479 -70.231) (xy 21.971 -70.231)
				)
			)
		)
		(zone
			(layer "F.Cu")
			(hatch none 0.5)
			(connect_pads
				(clearance 0)
			)
			(min_thickness 0.25)
			(keepout
				(tracks not_allowed)
				(vias allowed)
				(pads allowed)
				(copperpour not_allowed)
				(footprints allowed)
			)
			(placement
				(enabled no)
				(sheetname "")
			)
			(fill
				(thermal_gap 0.5)
				(thermal_bridge_width 0.5)
				(island_removal_mode 0)
			)
			(polygon
				(pts
					(xy 21.971 -70.231) (xy 22.479 -70.231) (xy 22.479 -70.612) (xy 21.971 -70.612)
				)
			)
		)
	)
	(footprint ""
		(layer "F.Cu")
		(at 471.513916 -24.49322)
		(property "Reference" "EU8E1"
			(at -0.508 -1.49733 0)
			(unlocked yes)
			(layer "F.SilkS")
			(effects
				(font
					(size 0.7874 0.5842)
					(thickness 0.1524)
				)
			)
		)
		(property "Value" ""
			(at 0 0 0)
			(layer "F.Fab")
			(effects
				(font
					(size 1.27 1.27)
				)
			)
		)
		(duplicate_pad_numbers_are_jumpers no)
		(fp_line
			(start -0.747014 -0.78994)
			(end 2.853182 -0.78994)
			(stroke
				(width 0.1524)
				(type default)
			)
			(layer "F.SilkS")
		)
		(fp_line
			(start -0.747014 3.301492)
			(end -0.747014 -0.78994)
			(stroke
				(width 0.1524)
				(type default)
			)
			(layer "F.SilkS")
		)
		(fp_line
			(start 2.853182 -0.78994)
			(end 2.853182 3.301492)
			(stroke
				(width 0.1524)
				(type default)
			)
			(layer "F.SilkS")
		)
		(fp_circle
			(center -1.238504 -0.803148)
			(end -1.111504 -0.803148)
			(stroke
				(width 0.254)
				(type default)
			)
			(fill no)
			(layer "F.SilkS")
		)
		(fp_poly
			(pts
				(xy -0.747014 -0.78994) (xy -0.747014 4.310126) (xy 2.853182 4.310126) (xy 2.853182 -0.78994)
			)
			(stroke
				(width 0)
				(type default)
			)
			(fill no)
			(layer "F.CrtYd")
		)
		(fp_line
			(start -0.747014 -0.78994)
			(end 2.853182 -0.78994)
			(stroke
				(width 0.1)
				(type default)
			)
			(layer "F.Fab")
		)
		(fp_line
			(start -0.747014 4.310126)
			(end -0.747014 -0.78994)
			(stroke
				(width 0.1)
				(type default)
			)
			(layer "F.Fab")
		)
		(fp_line
			(start 2.853182 -0.78994)
			(end 2.853182 4.310126)
			(stroke
				(width 0.1)
				(type default)
			)
			(layer "F.Fab")
		)
		(fp_line
			(start 2.853182 4.310126)
			(end -0.747014 4.310126)
			(stroke
				(width 0.1)
				(type default)
			)
			(layer "F.Fab")
		)
		(fp_circle
			(center -1.238504 -0.803148)
			(end -1.111504 -0.803148)
			(stroke
				(width 0.254)
				(type default)
			)
			(fill no)
			(layer "F.Fab")
		)
		(pad "1" smd rect
			(at 0 0)
			(size 0.3302 0.3302)
			(layers "F.Cu" "F.Mask" "F.Paste")
			(net "VR_P3V3_STBY_UGATE")
		)
		(pad "2" smd rect
			(at 1.366774 0.002032)
			(size 1.8034 0.508)
			(layers "F.Cu" "F.Mask" "F.Paste")
			(net "VR_FET_SW_P12V_STBY_P3V3_STBY")
		)
		(pad "3" smd custom
			(at 1.053084 2.19202)
			(size 0.56515 0.56515)
			(layers "F.Cu" "F.Mask" "F.Paste")
			(net "GND")
			(options
				(clearance outline)
				(anchor circle)
			)
			(primitives
				(gr_poly
					(pts
						(xy -1.2065 0.3937) (xy -1.2065 -1.1303) (xy 1.2065 -1.1303) (xy 1.2065 1.1303) (xy -0.5969 1.1303)
						(xy -0.5969 0.3937)
					)
					(width 0)
					(fill yes)
				)
			)
		)
		(pad "4" smd rect
			(at 0 3.047238)
			(size 0.3302 0.3302)
			(layers "F.Cu" "F.Mask" "F.Paste")
			(net "VR_P3V3_STBY_LGATE")
		)
		(pad "5" smd rect
			(at 1.053084 4.02463)
			(size 3.5052 0.508)
			(layers "F.Cu" "F.Mask" "F.Paste")
			(net "VR_P3V3_STBY_PHASE")
		)
	)
	(footprint ""
		(layer "F.Cu")
		(at 449.69938 -34.7345 90)
		(property "Reference" "R25W9"
			(at 0 0 90)
			(layer "F.SilkS")
			(hide yes)
			(effects
				(font
					(size 1.27 1.27)
				)
			)
		)
		(property "Value" "*"
			(at 0.064008 -4.108196 90)
			(unlocked yes)
			(layer "F.Fab")
			(hide yes)
			(effects
				(font
					(size 1.27 1.016)
					(thickness 0.1524)
				)
			)
		)
		(property "Device Type" "120R2F-GP_RCL_GP-120R2F-GP,64.A"
			(at 0.064008 -5.632196 90)
			(unlocked yes)
			(layer "F.Fab")
			(hide yes)
			(effects
				(font
					(size 1.27 1.016)
					(thickness 0.1524)
				)
			)
		)
		(duplicate_pad_numbers_are_jumpers no)
		(fp_line
			(start 0.508 -0.9398)
			(end -0.508 -0.9398)
			(stroke
				(width 0.1524)
				(type default)
			)
			(layer "F.SilkS")
		)
		(fp_line
			(start -0.508 -0.9398)
			(end -0.508 0.9398)
			(stroke
				(width 0.1524)
				(type default)
			)
			(layer "F.SilkS")
		)
		(fp_rect
			(start -0.508 0.9398)
			(end 0.508 -0.9398)
			(stroke
				(width 0)
				(type default)
			)
			(fill no)
			(layer "F.CrtYd")
		)
		(fp_rect
			(start -0.508 0.9398)
			(end 0.508 -0.9398)
			(stroke
				(width 0)
				(type default)
			)
			(fill no)
			(layer "F.Fab")
		)
		(pad "1" smd custom
			(at 0 -0.4445 90)
			(size 0.1397 0.1397)
			(layers "F.Cu" "F.Mask" "F.Paste")
			(net "GND")
			(options
				(clearance outline)
				(anchor circle)
			)
			(primitives
				(gr_poly
					(pts
						(arc
							(start -0.1778 -0.2794)
							(mid -0.249642 -0.249642)
							(end -0.2794 -0.1778)
						)
						(arc
							(start -0.2794 0.1778)
							(mid -0.249642 0.249642)
							(end -0.1778 0.2794)
						)
						(arc
							(start 0.1778 0.2794)
							(mid 0.249642 0.249642)
							(end 0.2794 0.1778)
						)
						(arc
							(start 0.2794 -0.1778)
							(mid 0.249642 -0.249642)
							(end 0.1778 -0.2794)
						)
					)
					(width 0)
					(fill yes)
				)
			)
		)
		(pad "2" smd custom
			(at 0 0.4445 90)
			(size 0.1397 0.1397)
			(layers "F.Cu" "F.Mask" "F.Paste")
			(net "BMC_M_BA0")
			(options
				(clearance outline)
				(anchor circle)
			)
			(primitives
				(gr_poly
					(pts
						(arc
							(start -0.1778 -0.2794)
							(mid -0.249642 -0.249642)
							(end -0.2794 -0.1778)
						)
						(arc
							(start -0.2794 0.1778)
							(mid -0.249642 0.249642)
							(end -0.1778 0.2794)
						)
						(arc
							(start 0.1778 0.2794)
							(mid 0.249642 0.249642)
							(end 0.2794 0.1778)
						)
						(arc
							(start 0.2794 -0.1778)
							(mid 0.249642 -0.249642)
							(end 0.1778 -0.2794)
						)
					)
					(width 0)
					(fill yes)
				)
			)
		)
	)
)
